# S9S_MB_2U (Grand Teton) — schematic netlist excerpt (pin names and nets, part order shuffled) for the footprints in the layout excerpt that follows; sources: Cadence DE-HDL packaged netlist, KiCad conversion of 03242023_DA0F0TMBIJ0_F0T_Motherboard_J_brd_V01_OCP.brd

D98  Q_LED  IC  pkg SMLF  page 252 : A = LED_P5V ; C = GND
C1319  Q_CAP  1UF 25V 10% X6S  pkg C0402  page 244 : A = PWRGD_DSW_PWROK ; B = GND
C727  Q_CAP_DIFFBUS  DIFF BUS_0.22UF 6.3V 20% X6S  pkg C0201  page 176 : \1\ = P5E_CPU1_PE0_TX_C_DP<7> ; \2\ = P5E_CPU1_PE0_TX_DP<7>

(kicad_pcb
	(version 20260206)
	(generator "pcbnew")
	(generator_version "10.0")
	(general
		(thickness 1.6)
		(legacy_teardrops no)
	)
	(paper "A4")
	(title_block
		(title "03242023_DA0F0TMBIJ0_F0T_Motherboard_J_brd_V01_OCP.brd")
		(comment 1 "Grand Teton / footprints 2263-2265 of 6105")
	)
	(layers
		(0 "F.Cu" signal "TOP")
		(4 "In1.Cu" signal "GND")
		(6 "In2.Cu" signal "IN1")
		(8 "In3.Cu" signal "GND1")
		(10 "In4.Cu" signal "IN2")
		(12 "In5.Cu" signal "GND2")
		(14 "In6.Cu" signal "IN3")
		(16 "In7.Cu" signal "GND3")
		(18 "In8.Cu" signal "VCC")
		(20 "In9.Cu" signal "VCC1")
		(22 "In10.Cu" signal "GND4")
		(24 "In11.Cu" signal "IN4")
		(26 "In12.Cu" signal "GND5")
		(28 "In13.Cu" signal "IN5")
		(30 "In14.Cu" signal "GND6")
		(32 "In15.Cu" signal "IN6")
		(34 "In16.Cu" signal "GND7")
		(2 "B.Cu" signal "BOTTOM")
		(9 "F.Adhes" user "F.Adhesive")
		(11 "B.Adhes" user "B.Adhesive")
		(13 "F.Paste" user "Package Geometry/Pastemask Top")
		(15 "B.Paste" user "Package Geometry/Pastemask Bottom")
		(5 "F.SilkS" user "Ref Des/Silkscreen Top")
		(7 "B.SilkS" user "Ref Des/Silkscreen Bottom")
		(1 "F.Mask" user "Board Geometry/Soldermask Top")
		(3 "B.Mask" user "Board Geometry/Soldermask Bottom")
		(17 "Dwgs.User" user "User.Drawings")
		(19 "Cmts.User" user "User.Comments")
		(21 "Eco1.User" user "User.Eco1")
		(23 "Eco2.User" user "User.Eco2")
		(25 "Edge.Cuts" user "Board Geometry/Outline")
		(27 "Margin" user)
		(31 "F.CrtYd" user "Package Geometry/Place Bound Top")
		(29 "B.CrtYd" user "Package Geometry/Place Bound Bottom")
		(35 "F.Fab" user "Ref Des/Assembly Top")
		(33 "B.Fab" user "Ref Des/Assembly Bottom")
	)
	(footprint ""
		(layer "F.Cu")
		(at 73.374758 -402.371052 -90)
		(property "Reference" "C727"
			(at 0 0 270)
			(layer "F.SilkS")
			(hide yes)
			(effects
				(font
					(size 1.27 1.27)
				)
			)
		)
		(property "Value" ""
			(at 0 0 270)
			(layer "F.Fab")
			(effects
				(font
					(size 1.27 1.27)
				)
			)
		)
		(duplicate_pad_numbers_are_jumpers no)
		(fp_line
			(start -0.299974 0.150114)
			(end -0.299974 -0.150114)
			(stroke
				(width 0.1)
				(type default)
			)
			(layer "F.Fab")
		)
		(fp_line
			(start 0.299974 0.150114)
			(end -0.299974 0.150114)
			(stroke
				(width 0.1)
				(type default)
			)
			(layer "F.Fab")
		)
		(fp_line
			(start -0.299974 -0.150114)
			(end 0.299974 -0.150114)
			(stroke
				(width 0.1)
				(type default)
			)
			(layer "F.Fab")
		)
		(fp_line
			(start 0.299974 -0.150114)
			(end 0.299974 0.150114)
			(stroke
				(width 0.1)
				(type default)
			)
			(layer "F.Fab")
		)
		(pad "1" smd rect
			(at -0.2667 0 270)
			(size 0.3048 0.381)
			(layers "F.Cu" "F.Mask" "F.Paste")
			(net "P5E_CPU1_PE0_TX_C_DP<7>")
		)
		(pad "2" smd rect
			(at 0.2667 0 270)
			(size 0.3048 0.381)
			(layers "F.Cu" "F.Mask" "F.Paste")
			(net "P5E_CPU1_PE0_TX_DP<7>")
		)
	)
	(footprint ""
		(layer "F.Cu")
		(at 209.74558 -126.512828)
		(property "Reference" "C1319"
			(at 0 0 0)
			(layer "F.SilkS")
			(hide yes)
			(effects
				(font
					(size 1.27 1.27)
				)
			)
		)
		(property "Value" ""
			(at 0 0 0)
			(layer "F.Fab")
			(effects
				(font
					(size 1.27 1.27)
				)
			)
		)
		(duplicate_pad_numbers_are_jumpers no)
		(fp_line
			(start -0.7874 -0.4064)
			(end 0.7874 -0.4064)
			(stroke
				(width 0.1524)
				(type default)
			)
			(layer "F.SilkS")
		)
		(fp_line
			(start -0.7874 0.4064)
			(end -0.7874 -0.4064)
			(stroke
				(width 0.1524)
				(type default)
			)
			(layer "F.SilkS")
		)
		(fp_line
			(start 0.7874 -0.4064)
			(end 0.7874 0.4064)
			(stroke
				(width 0.1524)
				(type default)
			)
			(layer "F.SilkS")
		)
		(fp_line
			(start 0.7874 0.4064)
			(end -0.7874 0.4064)
			(stroke
				(width 0.1524)
				(type default)
			)
			(layer "F.SilkS")
		)
		(fp_line
			(start -0.67945 -0.305054)
			(end -0.12065 -0.305054)
			(stroke
				(width 0.1)
				(type default)
			)
			(layer "F.Fab")
		)
		(fp_line
			(start -0.67945 0.3048)
			(end -0.67945 -0.305054)
			(stroke
				(width 0.1)
				(type default)
			)
			(layer "F.Fab")
		)
		(fp_line
			(start -0.12065 -0.305054)
			(end -0.12065 -0.2794)
			(stroke
				(width 0.1)
				(type default)
			)
			(layer "F.Fab")
		)
		(fp_line
			(start -0.12065 -0.2794)
			(end 0.12065 -0.2794)
			(stroke
				(width 0.1)
				(type default)
			)
			(layer "F.Fab")
		)
		(fp_line
			(start -0.12065 0.2794)
			(end -0.12065 0.3048)
			(stroke
				(width 0.1)
				(type default)
			)
			(layer "F.Fab")
		)
		(fp_line
			(start -0.12065 0.3048)
			(end -0.67945 0.3048)
			(stroke
				(width 0.1)
				(type default)
			)
			(layer "F.Fab")
		)
		(fp_line
			(start 0.120396 0.2794)
			(end -0.12065 0.2794)
			(stroke
				(width 0.1)
				(type default)
			)
			(layer "F.Fab")
		)
		(fp_line
			(start 0.120396 0.3048)
			(end 0.120396 0.2794)
			(stroke
				(width 0.1)
				(type default)
			)
			(layer "F.Fab")
		)
		(fp_line
			(start 0.12065 -0.3048)
			(end 0.67945 -0.3048)
			(stroke
				(width 0.1)
				(type default)
			)
			(layer "F.Fab")
		)
		(fp_line
			(start 0.12065 -0.2794)
			(end 0.12065 -0.3048)
			(stroke
				(width 0.1)
				(type default)
			)
			(layer "F.Fab")
		)
		(fp_line
			(start 0.67945 -0.3048)
			(end 0.67945 0.3048)
			(stroke
				(width 0.1)
				(type default)
			)
			(layer "F.Fab")
		)
		(fp_line
			(start 0.67945 0.3048)
			(end 0.120396 0.3048)
			(stroke
				(width 0.1)
				(type default)
			)
			(layer "F.Fab")
		)
		(pad "1" smd circle
			(at -0.40005 0)
			(size 0 0)
			(layers "F.Cu" "F.Mask" "F.Paste")
			(net "PWRGD_DSW_PWROK")
		)
		(pad "2" smd circle
			(at 0.40005 0)
			(size 0 0)
			(layers "F.Cu" "F.Mask" "F.Paste")
			(net "GND")
		)
	)
	(footprint ""
		(layer "F.Cu")
		(at 90.397076 -79.078836)
		(property "Reference" "D98"
			(at -45.69841 38.649402 90)
			(unlocked yes)
			(layer "F.SilkS")
			(effects
				(font
					(size 0.635 0.4064)
					(thickness 0.1524)
				)
				(justify left)
			)
		)
		(property "Value" ""
			(at 0 0 0)
			(layer "F.Fab")
			(effects
				(font
					(size 1.27 1.27)
				)
			)
		)
		(duplicate_pad_numbers_are_jumpers no)
		(fp_line
			(start -0.90678 0.4826)
			(end -0.90678 -0.4699)
			(stroke
				(width 0.1524)
				(type default)
			)
			(layer "F.SilkS")
		)
		(fp_line
			(start -0.89408 -0.4826)
			(end 0.90678 -0.4826)
			(stroke
				(width 0.1524)
				(type default)
			)
			(layer "F.SilkS")
		)
		(fp_line
			(start -0.79248 -0.4826)
			(end 1.03378 -0.4826)
			(stroke
				(width 0.1524)
				(type default)
			)
			(layer "F.SilkS")
		)
		(fp_line
			(start -0.64008 -0.4826)
			(end 1.16078 -0.4826)
			(stroke
				(width 0.1524)
				(type default)
			)
			(layer "F.SilkS")
		)
		(fp_line
			(start 0.90678 -0.4826)
			(end 0.90678 0.4826)
			(stroke
				(width 0.1524)
				(type default)
			)
			(layer "F.SilkS")
		)
		(fp_line
			(start 0.90678 0.4826)
			(end -0.90678 0.4826)
			(stroke
				(width 0.1524)
				(type default)
			)
			(layer "F.SilkS")
		)
		(fp_line
			(start 1.03378 -0.4826)
			(end 1.03378 0.4826)
			(stroke
				(width 0.1524)
				(type default)
			)
			(layer "F.SilkS")
		)
		(fp_line
			(start 1.03378 0.4826)
			(end -0.79248 0.4826)
			(stroke
				(width 0.1524)
				(type default)
			)
			(layer "F.SilkS")
		)
		(fp_line
			(start 1.16078 -0.4826)
			(end 1.16078 0.4826)
			(stroke
				(width 0.1524)
				(type default)
			)
			(layer "F.SilkS")
		)
		(fp_line
			(start 1.16078 0.4826)
			(end -0.64008 0.4826)
			(stroke
				(width 0.1524)
				(type default)
			)
			(layer "F.SilkS")
		)
		(fp_line
			(start -0.499872 -0.249936)
			(end 0.499872 -0.249936)
			(stroke
				(width 0.1)
				(type default)
			)
			(layer "F.Fab")
		)
		(fp_line
			(start -0.499872 0.249936)
			(end -0.499872 -0.249936)
			(stroke
				(width 0.1)
				(type default)
			)
			(layer "F.Fab")
		)
		(fp_line
			(start 0.499872 -0.249936)
			(end 0.499872 0.249936)
			(stroke
				(width 0.1)
				(type default)
			)
			(layer "F.Fab")
		)
		(fp_line
			(start 0.499872 0.249936)
			(end -0.499872 0.249936)
			(stroke
				(width 0.1)
				(type default)
			)
			(layer "F.Fab")
		)
		(pad "A" smd rect
			(at -0.47498 0)
			(size 0.6096 0.7112)
			(layers "F.Cu" "F.Mask" "F.Paste")
			(net "LED_P5V")
		)
		(pad "C" smd rect
			(at 0.47498 0)
			(size 0.6096 0.7112)
			(layers "F.Cu" "F.Mask" "F.Paste")
			(net "GND")
		)
	)
)
